# T6G (Grand Teton) — schematic netlist excerpt (pin names and nets, part order shuffled) for the footprints in the layout excerpt that follows; sources: Cadence DE-HDL packaged netlist, KiCad conversion of 04192023_DAF0TMB3IC0_F0TG_MB_C_brd_V02_OCP.brd

J100  SCONN288_DDR506112002KQ  IO  pkg DDR288S_1-1VXC  page 106
  VIN_BULK0  = P12V_MEM_CPU1
  RFU0  = NC
  VIN_MGMT  = P3V3_AUX
  HSCL  = I3C_SPD_DDRI_CPU1_SCL
  HSDA  = I3C_SPD_DDRI_CPU1_SDA
  VSS0  = GND
  DQ0_A  = M_I_CPU1_SA_DQ<0>
  VSS1  = GND
  DQ1_A  = M_I_CPU1_SA_DQ<1>
  VSS2  = GND
  DQS0_A_T  = M_I_CPU1_SA_DQS_DP<0>
  DQS0_A_C  = M_I_CPU1_SA_DQS_DN<0>
  VSS3  = GND
  DQ4_A  = M_I_CPU1_SA_DQ<4>
  VSS4  = GND
  DQ5_A  = M_I_CPU1_SA_DQ<5>
  VSS5  = GND
  DQ8_A  = M_I_CPU1_SA_DQ<8>
  VSS6  = GND
  DQ9_A  = M_I_CPU1_SA_DQ<9>
  VSS7  = GND
  DQS1_A_T  = M_I_CPU1_SA_DQS_DP<1>
  DQS1_A_C  = M_I_CPU1_SA_DQS_DN<1>
  VSS8  = GND
  DQ12_A  = M_I_CPU1_SA_DQ<12>
  VSS9  = GND
  DQ13_A  = M_I_CPU1_SA_DQ<13>
  VSS10  = GND
  DQ16_A  = M_I_CPU1_SA_DQ<16>
  VSS11  = GND
  DQ17_A  = M_I_CPU1_SA_DQ<17>
  VSS12  = GND
  DQS2_A_T  = M_I_CPU1_SA_DQS_DP<2>
  DQS2_A_C  = M_I_CPU1_SA_DQS_DN<2>
  VSS13  = GND
  DQ20_A  = M_I_CPU1_SA_DQ<20>
  VSS14  = GND
  DQ21_A  = M_I_CPU1_SA_DQ<21>
  VSS15  = GND
  DQ24_A  = M_I_CPU1_SA_DQ<24>
  VSS16  = GND
  DQ25_A  = M_I_CPU1_SA_DQ<25>
  VSS17  = GND
  DQS3_A_T  = M_I_CPU1_SA_DQS_DP<3>
  DQS3_A_C  = M_I_CPU1_SA_DQS_DN<3>
  VSS18  = GND
  DQ28_A  = M_I_CPU1_SA_DQ<28>
  VSS19  = GND
  DQ29_A  = M_I_CPU1_SA_DQ<29>
  VSS20  = GND
  CB0_A  = M_I_CPU1_SA_CB<0>
  VSS21  = GND
  CB1_A  = M_I_CPU1_SA_CB<1>
  VSS22  = GND
  DQS4_A_T  = M_I_CPU1_SA_DQS_DP<4>
  DQS4_A_C  = M_I_CPU1_SA_DQS_DN<4>
  VSS23  = GND
  CB4_A  = M_I_CPU1_SA_CB<4>
  VSS24  = GND
  CB5_A  = M_I_CPU1_SA_CB<5>
  VSS25  = GND
  ALERT_N  = M_I_CPU1_ALERT_N
  VSS26  = GND
  CS0_A_N  = M_I_CPU1_SA_CS_N<0>
  VSS27  = GND
  CA0_A  = M_I_CPU1_SA_CA<0>
  VSS28  = GND
  CA2_A  = M_I_CPU1_SA_CA<2>
  VSS29  = GND
  CA4_A  = M_I_CPU1_SA_CA<4>
  VSS30  = GND
  CA6_A  = M_I_CPU1_SA_CA<6>
  VSS31  = GND
  PAR_A  = M_I_CPU1_SA_PAR
  VSS32  = GND
  CA0_B  = M_I_CPU1_SB_CA<0>
  VSS33  = GND
  CA2_B  = M_I_CPU1_SB_CA<2>
  VSS34  = GND
  CA4_B  = M_I_CPU1_SB_CA<4>
  VSS35  = GND
  CA6_B  = M_I_CPU1_SB_CA<6>
  VSS36  = GND
  CS0_B_N  = M_I_CPU1_SB_CS_N<0>
  VSS37  = GND
  \lbd||rsp_a_n\  = M_I_CPU1_SA_RSP<0>
  \lbs||rsp_b_n\  = M_I_CPU1_SB_RSP<0>
  VSS38  = GND
  CB4_B  = M_I_CPU1_SB_CB<4>
  VSS39  = GND
  CB5_B  = M_I_CPU1_SB_CB<5>
  VSS40  = GND
  \dqs9_b_t||tdqs9_b_t||dbi4_b_n\  = M_I_CPU1_SB_DQS_DP<9>
  \dqs9_b_c||tdqs9_b_c\  = M_I_CPU1_SB_DQS_DN<9>
  VSS41  = GND
  CB0_B  = M_I_CPU1_SB_CB<0>
  VSS42  = GND
  CB1_B  = M_I_CPU1_SB_CB<1>
  VSS43  = GND
  DQ0_B  = M_I_CPU1_SB_DQ<0>
  VSS44  = GND
  DQ1_B  = M_I_CPU1_SB_DQ<1>
  VSS45  = GND
  DQS0_B_T  = M_I_CPU1_SB_DQS_DP<0>
  DQS0_B_C  = M_I_CPU1_SB_DQS_DN<0>
  VSS46  = GND
  DQ4_B  = M_I_CPU1_SB_DQ<4>
  VSS47  = GND
  DQ5_B  = M_I_CPU1_SB_DQ<5>
  VSS48  = GND
  DQ8_B  = M_I_CPU1_SB_DQ<8>
  VSS49  = GND
  DQ9_B  = M_I_CPU1_SB_DQ<9>
  VSS50  = GND
  DQS1_B_T  = M_I_CPU1_SB_DQS_DP<1>
  DQS1_B_C  = M_I_CPU1_SB_DQS_DN<1>
  VSS51  = GND
  DQ12_B  = M_I_CPU1_SB_DQ<12>
  VSS52  = GND
  DQ13_B  = M_I_CPU1_SB_DQ<13>
  VSS53  = GND
  DQ16_B  = M_I_CPU1_SB_DQ<16>
  VSS54  = GND
  DQ17_B  = M_I_CPU1_SB_DQ<17>
  VSS55  = GND
  DQS2_B_T  = M_I_CPU1_SB_DQS_DP<2>
  DQS2_B_C  = M_I_CPU1_SB_DQS_DN<2>
  VSS56  = GND
  DQ20_B  = M_I_CPU1_SB_DQ<20>
  VSS57  = GND
  DQ21_B  = M_I_CPU1_SB_DQ<21>
  VSS58  = GND
  DQ24_B  = M_I_CPU1_SB_DQ<24>
  VSS59  = GND
  DQ25_B  = M_I_CPU1_SB_DQ<25>
  VSS60  = GND
  DQS3_B_T  = M_I_CPU1_SB_DQS_DP<3>
  DQS3_B_C  = M_I_CPU1_SB_DQS_DN<3>
  VSS61  = GND
  DQ28_B  = M_I_CPU1_SB_DQ<28>
  VSS62  = GND
  DQ29_B  = M_I_CPU1_SB_DQ<29>
  VSS63  = GND
  RFU1  = NC
  VIN_BULK1  = P12V_MEM_CPU1
  VIN_BULK2  = P12V_MEM_CPU1
  \pwr_good||fail_n\  = PWRGD_CHI_CPU1_DIMM
  HAS  = PD_CHI_CPU1_DIMM_SAA
  RFU2  = NC
  RFU3  = NC
  VSS64  = GND
  DQ2_A  = M_I_CPU1_SA_DQ<2>
  VSS65  = GND
  DQ3_A  = M_I_CPU1_SA_DQ<3>
  VSS66  = GND
  \dqs5_a_c||tdqs5_a_c||dqs5_a_t||tdqs5_a_t\  = M_I_CPU1_SA_DQS_DN<5>
  \dqs5_a_t||tdqs5_a_t\  = M_I_CPU1_SA_DQS_DP<5>
  VSS67  = GND
  DQ6_A  = M_I_CPU1_SA_DQ<6>
  VSS68  = GND
  DQ7_A  = M_I_CPU1_SA_DQ<7>
  VSS69  = GND
  DQ10_A  = M_I_CPU1_SA_DQ<10>
  VSS70  = GND
  DQ11_A  = M_I_CPU1_SA_DQ<11>
  VSS71  = GND
  \dqs6_a_c||tdqs6_a_c||dqs6_a_t||tdqs6_a_t\  = M_I_CPU1_SA_DQS_DN<6>
  \dqs6_a_t||tdqs6_a_t\  = M_I_CPU1_SA_DQS_DP<6>
  VSS72  = GND
  DQ14_A  = M_I_CPU1_SA_DQ<14>
  VSS73  = GND
  DQ15_A  = M_I_CPU1_SA_DQ<15>
  VSS74  = GND
  DQ18_A  = M_I_CPU1_SA_DQ<18>
  VSS75  = GND
  DQ19_A  = M_I_CPU1_SA_DQ<19>
  VSS76  = GND
  \dqs7_a_c||tdqs7_a_c\  = M_I_CPU1_SA_DQS_DN<7>
  \dqs7_a_t||tdqs7_a_t\  = M_I_CPU1_SA_DQS_DP<7>
  VSS77  = GND
  DQ22_A  = M_I_CPU1_SA_DQ<22>
  VSS78  = GND
  DQ23_A  = M_I_CPU1_SA_DQ<23>
  VSS79  = GND
  DQ26_A  = M_I_CPU1_SA_DQ<26>
  VSS80  = GND
  DQ27_A  = M_I_CPU1_SA_DQ<27>
  VSS81  = GND
  \dqs8_a_c||tdqs8_a_c\  = M_I_CPU1_SA_DQS_DN<8>
  \dqs8_a_t||tdqs8_a_t\  = M_I_CPU1_SA_DQS_DP<8>
  VSS82  = GND
  DQ30_A  = M_I_CPU1_SA_DQ<30>
  VSS83  = GND
  DQ31_A  = M_I_CPU1_SA_DQ<31>
  VSS84  = GND
  CB2_A  = M_I_CPU1_SA_CB<2>
  VSS85  = GND
  CB3_A  = M_I_CPU1_SA_CB<3>
  VSS86  = GND
  \dqs9_a_c||tdqs9_a_c\  = M_I_CPU1_SA_DQS_DN<9>
  \dqs9_a_t||tdqs9_a_t\  = M_I_CPU1_SA_DQS_DP<9>
  VSS87  = GND
  CB6_A  = M_I_CPU1_SA_CB<6>
  VSS88  = GND
  CB7_A  = M_I_CPU1_SA_CB<7>
  VSS89  = GND
  RESET_N  = M_I_CPU1_RESET_N
  VSS90  = GND
  CS1_A_N  = M_I_CPU1_SA_CS_N<1>
  VSS91  = GND
  CA1_A  = M_I_CPU1_SA_CA<1>
  VSS92  = GND
  CA3_A  = M_I_CPU1_SA_CA<3>
  VSS93  = GND
  CA5_A  = M_I_CPU1_SA_CA<5>
  VSS94  = GND
  CK_T  = M_I_CPU1_CLK_DP<0>
  CK_C  = M_I_CPU1_CLK_DN<0>
  VSS95  = GND
  RFU4  = NC
  CA1_B  = M_I_CPU1_SB_CA<1>
  VSS96  = GND
  CA3_B  = M_I_CPU1_SB_CA<3>
  VSS97  = GND
  CA5_B  = M_I_CPU1_SB_CA<5>
  VSS98  = GND
  PAR_B  = M_I_CPU1_SB_PAR
  VSS99  = GND
  CS1_B_N  = M_I_CPU1_SB_CS_N<1>
  VSS100  = GND
  RFU5  = NC
  RFU6  = NC
  VSS101  = GND
  CB6_B  = M_I_CPU1_SB_CB<6>
  VSS102  = GND
  CB7_B  = M_I_CPU1_SB_CB<7>
  VSS103  = GND
  DQS4_B_C  = M_I_CPU1_SB_DQS_DN<4>
  DQS4_B_T  = M_I_CPU1_SB_DQS_DP<4>
  VSS104  = GND
  CB2_B  = M_I_CPU1_SB_CB<2>
  VSS105  = GND
  CB3_B  = M_I_CPU1_SB_CB<3>
  VSS106  = GND
  DQ2_B  = M_I_CPU1_SB_DQ<2>
  VSS107  = GND
  DQ3_B  = M_I_CPU1_SB_DQ<3>
  VSS108  = GND
  \dqs5_b_c||tdqs5_b_c\  = M_I_CPU1_SB_DQS_DN<5>
  \dqs5_b_t||tdqs5_b_t\  = M_I_CPU1_SB_DQS_DP<5>
  VSS109  = GND
  DQ6_B  = M_I_CPU1_SB_DQ<6>
  VSS110  = GND
  DQ7_B  = M_I_CPU1_SB_DQ<7>
  VSS111  = GND
  DQ10_B  = M_I_CPU1_SB_DQ<10>
  VSS112  = GND
  DQ11_B  = M_I_CPU1_SB_DQ<11>
  VSS113  = GND
  \dqs6_b_c||tdqs6_b_c\  = M_I_CPU1_SB_DQS_DN<6>
  \dqs6_b_t||tdqs6_b_t\  = M_I_CPU1_SB_DQS_DP<6>
  VSS114  = GND
  DQ14_B  = M_I_CPU1_SB_DQ<14>
  VSS115  = GND
  DQ15_B  = M_I_CPU1_SB_DQ<15>
  VSS116  = GND
  DQ18_B  = M_I_CPU1_SB_DQ<18>
  VSS117  = GND
  DQ19_B  = M_I_CPU1_SB_DQ<19>
  VSS118  = GND
  \dqs7_b_c||tdqs7_b_c\  = M_I_CPU1_SB_DQS_DN<7>
  \dqs7_b_t||tdqs7_b_t\  = M_I_CPU1_SB_DQS_DP<7>
  VSS119  = GND
  DQ22_B  = M_I_CPU1_SB_DQ<22>
  VSS120  = GND
  DQ23_B  = M_I_CPU1_SB_DQ<23>
  VSS121  = GND
  DQ26_B  = M_I_CPU1_SB_DQ<26>
  VSS122  = GND
  DQ27_B  = M_I_CPU1_SB_DQ<27>
  VSS123  = GND
  \dqs8_b_c||tdqs8_b_c\  = M_I_CPU1_SB_DQS_DN<8>
  \dqs8_b_t||tdqs8_b_t\  = M_I_CPU1_SB_DQS_DP<8>
  VSS124  = GND
  DQ30_B  = M_I_CPU1_SB_DQ<30>
  VSS125  = GND
  DQ31_B  = M_I_CPU1_SB_DQ<31>
  VSS126  = GND
  G1  = GND
  G2  = GND
  G3  = GND

(kicad_pcb
	(version 20260206)
	(generator "pcbnew")
	(generator_version "10.0")
	(general
		(thickness 1.6)
		(legacy_teardrops no)
	)
	(paper "A4")
	(title_block
		(title "04192023_DAF0TMB3IC0_F0TG_MB_C_brd_V02_OCP.brd")
		(comment 1 "Grand Teton / footprint 230 of 8354 (J100), pads 93-138 of 291")
	)
	(layers
		(0 "F.Cu" signal "TOP")
		(4 "In1.Cu" signal "GND")
		(6 "In2.Cu" signal "IN1")
		(8 "In3.Cu" signal "GND1")
		(10 "In4.Cu" signal "IN2")
		(12 "In5.Cu" signal "GND2")
		(14 "In6.Cu" signal "IN3")
		(16 "In7.Cu" signal "GND3")
		(18 "In8.Cu" signal "VCC")
		(20 "In9.Cu" signal "VCC1")
		(22 "In10.Cu" signal "GND4")
		(24 "In11.Cu" signal "IN4")
		(26 "In12.Cu" signal "GND5")
		(28 "In13.Cu" signal "IN5")
		(30 "In14.Cu" signal "GND6")
		(32 "In15.Cu" signal "IN6")
		(34 "In16.Cu" signal "GND7")
		(2 "B.Cu" signal "BOTTOM")
		(9 "F.Adhes" user "F.Adhesive")
		(11 "B.Adhes" user "B.Adhesive")
		(13 "F.Paste" user "Package Geometry/Pastemask Top")
		(15 "B.Paste" user "Package Geometry/Pastemask Bottom")
		(5 "F.SilkS" user "Ref Des/Silkscreen Top")
		(7 "B.SilkS" user "Ref Des/Silkscreen Bottom")
		(1 "F.Mask" user "Board Geometry/Soldermask Top")
		(3 "B.Mask" user "Board Geometry/Soldermask Bottom")
		(17 "Dwgs.User" user "User.Drawings")
		(19 "Cmts.User" user "User.Comments")
		(21 "Eco1.User" user "User.Eco1")
		(23 "Eco2.User" user "User.Eco2")
		(25 "Edge.Cuts" user "Board Geometry/Outline")
		(27 "Margin" user)
		(31 "F.CrtYd" user "Package Geometry/Place Bound Top")
		(29 "B.CrtYd" user "Package Geometry/Place Bound Bottom")
		(35 "F.Fab" user "Ref Des/Assembly Top")
		(33 "B.Fab" user "Ref Des/Assembly Bottom")
	)
	(footprint ""
		(layer "F.Cu")
		(at 181.566058 -255.560322 180)
		(property "Reference" "J100"
			(at -2.7178 -81.857088 0)
			(unlocked yes)
			(layer "F.SilkS")
			(effects
				(font
					(size 0.7874 0.5842)
					(thickness 0.1524)
				)
			)
		)
		(property "Value" ""
			(at 0 0 180)
			(layer "F.Fab")
			(effects
				(font
					(size 1.27 1.27)
				)
			)
		)
		(duplicate_pad_numbers_are_jumpers no)
		(pad "93" smd rect
			(at -2.050034 19.975068 90)
			(size 0.519938 1.4986)
			(layers "F.Cu" "F.Mask" "F.Paste")
			(net "M_I_CPU1_SB_DQS_DP<9>")
		)
		(pad "94" smd rect
			(at -2.050034 20.824952 90)
			(size 0.519938 1.4986)
			(layers "F.Cu" "F.Mask" "F.Paste")
			(net "M_I_CPU1_SB_DQS_DN<9>")
		)
		(pad "95" smd rect
			(at -2.050034 21.67509 90)
			(size 0.519938 1.4986)
			(layers "F.Cu" "F.Mask" "F.Paste")
			(net "GND")
		)
		(pad "96" smd rect
			(at -2.050034 22.524974 90)
			(size 0.519938 1.4986)
			(layers "F.Cu" "F.Mask" "F.Paste")
			(net "M_I_CPU1_SB_CB<0>")
		)
		(pad "97" smd rect
			(at -2.050034 23.375112 90)
			(size 0.519938 1.4986)
			(layers "F.Cu" "F.Mask" "F.Paste")
			(net "GND")
		)
		(pad "98" smd rect
			(at -2.050034 24.224996 90)
			(size 0.519938 1.4986)
			(layers "F.Cu" "F.Mask" "F.Paste")
			(net "M_I_CPU1_SB_CB<1>")
		)
		(pad "99" smd rect
			(at -2.050034 25.07488 90)
			(size 0.519938 1.4986)
			(layers "F.Cu" "F.Mask" "F.Paste")
			(net "GND")
		)
		(pad "100" smd rect
			(at -2.050034 25.925018 90)
			(size 0.519938 1.4986)
			(layers "F.Cu" "F.Mask" "F.Paste")
			(net "M_I_CPU1_SB_DQ<0>")
		)
		(pad "101" smd rect
			(at -2.050034 26.774902 90)
			(size 0.519938 1.4986)
			(layers "F.Cu" "F.Mask" "F.Paste")
			(net "GND")
		)
		(pad "102" smd rect
			(at -2.050034 27.62504 90)
			(size 0.519938 1.4986)
			(layers "F.Cu" "F.Mask" "F.Paste")
			(net "M_I_CPU1_SB_DQ<1>")
		)
		(pad "103" smd rect
			(at -2.050034 28.474924 90)
			(size 0.519938 1.4986)
			(layers "F.Cu" "F.Mask" "F.Paste")
			(net "GND")
		)
		(pad "104" smd rect
			(at -2.050034 29.325062 90)
			(size 0.519938 1.4986)
			(layers "F.Cu" "F.Mask" "F.Paste")
			(net "M_I_CPU1_SB_DQS_DP<0>")
		)
		(pad "105" smd rect
			(at -2.050034 30.174946 90)
			(size 0.519938 1.4986)
			(layers "F.Cu" "F.Mask" "F.Paste")
			(net "M_I_CPU1_SB_DQS_DN<0>")
		)
		(pad "106" smd rect
			(at -2.050034 31.025084 90)
			(size 0.519938 1.4986)
			(layers "F.Cu" "F.Mask" "F.Paste")
			(net "GND")
		)
		(pad "107" smd rect
			(at -2.050034 31.874968 90)
			(size 0.519938 1.4986)
			(layers "F.Cu" "F.Mask" "F.Paste")
			(net "M_I_CPU1_SB_DQ<4>")
		)
		(pad "108" smd rect
			(at -2.050034 32.725106 90)
			(size 0.519938 1.4986)
			(layers "F.Cu" "F.Mask" "F.Paste")
			(net "GND")
		)
		(pad "109" smd rect
			(at -2.050034 33.57499 90)
			(size 0.519938 1.4986)
			(layers "F.Cu" "F.Mask" "F.Paste")
			(net "M_I_CPU1_SB_DQ<5>")
		)
		(pad "110" smd rect
			(at -2.050034 34.425128 90)
			(size 0.519938 1.4986)
			(layers "F.Cu" "F.Mask" "F.Paste")
			(net "GND")
		)
		(pad "111" smd rect
			(at -2.050034 35.275012 90)
			(size 0.519938 1.4986)
			(layers "F.Cu" "F.Mask" "F.Paste")
			(net "M_I_CPU1_SB_DQ<8>")
		)
		(pad "112" smd rect
			(at -2.050034 36.124896 90)
			(size 0.519938 1.4986)
			(layers "F.Cu" "F.Mask" "F.Paste")
			(net "GND")
		)
		(pad "113" smd rect
			(at -2.050034 36.975034 90)
			(size 0.519938 1.4986)
			(layers "F.Cu" "F.Mask" "F.Paste")
			(net "M_I_CPU1_SB_DQ<9>")
		)
		(pad "114" smd rect
			(at -2.050034 37.824918 90)
			(size 0.519938 1.4986)
			(layers "F.Cu" "F.Mask" "F.Paste")
			(net "GND")
		)
		(pad "115" smd rect
			(at -2.050034 38.675056 90)
			(size 0.519938 1.4986)
			(layers "F.Cu" "F.Mask" "F.Paste")
			(net "M_I_CPU1_SB_DQS_DP<1>")
		)
		(pad "116" smd rect
			(at -2.050034 39.52494 90)
			(size 0.519938 1.4986)
			(layers "F.Cu" "F.Mask" "F.Paste")
			(net "M_I_CPU1_SB_DQS_DN<1>")
		)
		(pad "117" smd rect
			(at -2.050034 40.375078 90)
			(size 0.519938 1.4986)
			(layers "F.Cu" "F.Mask" "F.Paste")
			(net "GND")
		)
		(pad "118" smd rect
			(at -2.050034 41.224962 90)
			(size 0.519938 1.4986)
			(layers "F.Cu" "F.Mask" "F.Paste")
			(net "M_I_CPU1_SB_DQ<12>")
		)
		(pad "119" smd rect
			(at -2.050034 42.0751 90)
			(size 0.519938 1.4986)
			(layers "F.Cu" "F.Mask" "F.Paste")
			(net "GND")
		)
		(pad "120" smd rect
			(at -2.050034 42.924984 90)
			(size 0.519938 1.4986)
			(layers "F.Cu" "F.Mask" "F.Paste")
			(net "M_I_CPU1_SB_DQ<13>")
		)
		(pad "121" smd rect
			(at -2.050034 43.775122 90)
			(size 0.519938 1.4986)
			(layers "F.Cu" "F.Mask" "F.Paste")
			(net "GND")
		)
		(pad "122" smd rect
			(at -2.050034 44.625006 90)
			(size 0.519938 1.4986)
			(layers "F.Cu" "F.Mask" "F.Paste")
			(net "M_I_CPU1_SB_DQ<16>")
		)
		(pad "123" smd rect
			(at -2.050034 45.47489 90)
			(size 0.519938 1.4986)
			(layers "F.Cu" "F.Mask" "F.Paste")
			(net "GND")
		)
		(pad "124" smd rect
			(at -2.050034 46.325028 90)
			(size 0.519938 1.4986)
			(layers "F.Cu" "F.Mask" "F.Paste")
			(net "M_I_CPU1_SB_DQ<17>")
		)
		(pad "125" smd rect
			(at -2.050034 47.174912 90)
			(size 0.519938 1.4986)
			(layers "F.Cu" "F.Mask" "F.Paste")
			(net "GND")
		)
		(pad "126" smd rect
			(at -2.050034 48.02505 90)
			(size 0.519938 1.4986)
			(layers "F.Cu" "F.Mask" "F.Paste")
			(net "M_I_CPU1_SB_DQS_DP<2>")
		)
		(pad "127" smd rect
			(at -2.050034 48.874934 90)
			(size 0.519938 1.4986)
			(layers "F.Cu" "F.Mask" "F.Paste")
			(net "M_I_CPU1_SB_DQS_DN<2>")
		)
		(pad "128" smd rect
			(at -2.050034 49.725072 90)
			(size 0.519938 1.4986)
			(layers "F.Cu" "F.Mask" "F.Paste")
			(net "GND")
		)
		(pad "129" smd rect
			(at -2.050034 50.574956 90)
			(size 0.519938 1.4986)
			(layers "F.Cu" "F.Mask" "F.Paste")
			(net "M_I_CPU1_SB_DQ<20>")
		)
		(pad "130" smd rect
			(at -2.050034 51.425094 90)
			(size 0.519938 1.4986)
			(layers "F.Cu" "F.Mask" "F.Paste")
			(net "GND")
		)
		(pad "131" smd rect
			(at -2.050034 52.274978 90)
			(size 0.519938 1.4986)
			(layers "F.Cu" "F.Mask" "F.Paste")
			(net "M_I_CPU1_SB_DQ<21>")
		)
		(pad "132" smd rect
			(at -2.050034 53.125116 90)
			(size 0.519938 1.4986)
			(layers "F.Cu" "F.Mask" "F.Paste")
			(net "GND")
		)
		(pad "133" smd rect
			(at -2.050034 53.975 90)
			(size 0.519938 1.4986)
			(layers "F.Cu" "F.Mask" "F.Paste")
			(net "M_I_CPU1_SB_DQ<24>")
		)
		(pad "134" smd rect
			(at -2.050034 54.824884 90)
			(size 0.519938 1.4986)
			(layers "F.Cu" "F.Mask" "F.Paste")
			(net "GND")
		)
		(pad "135" smd rect
			(at -2.050034 55.675022 90)
			(size 0.519938 1.4986)
			(layers "F.Cu" "F.Mask" "F.Paste")
			(net "M_I_CPU1_SB_DQ<25>")
		)
		(pad "136" smd rect
			(at -2.050034 56.524906 90)
			(size 0.519938 1.4986)
			(layers "F.Cu" "F.Mask" "F.Paste")
			(net "GND")
		)
		(pad "137" smd rect
			(at -2.050034 57.375044 90)
			(size 0.519938 1.4986)
			(layers "F.Cu" "F.Mask" "F.Paste")
			(net "M_I_CPU1_SB_DQS_DP<3>")
		)
		(pad "138" smd rect
			(at -2.050034 58.224928 90)
			(size 0.519938 1.4986)
			(layers "F.Cu" "F.Mask" "F.Paste")
			(net "M_I_CPU1_SB_DQS_DN<3>")
		)
	)
)
